(kicad_pcb
	(version 20260206)
	(generator "pcbnew")
	(generator_version "10.0")
	(general
		(thickness 1.6)
		(legacy_teardrops no)
	)
	(paper "A4")
	(title_block
		(title "04192023_DAF0TMB3IC0_F0TG_MB_C_brd_V02_OCP.brd")
		(comment 1 "Grand Teton / footprints 968-974 of 8354")
	)
	(layers
		(0 "F.Cu" signal "TOP")
		(4 "In1.Cu" signal "GND")
		(6 "In2.Cu" signal "IN1")
		(8 "In3.Cu" signal "GND1")
		(10 "In4.Cu" signal "IN2")
		(12 "In5.Cu" signal "GND2")
		(14 "In6.Cu" signal "IN3")
		(16 "In7.Cu" signal "GND3")
		(18 "In8.Cu" signal "VCC")
		(20 "In9.Cu" signal "VCC1")
		(22 "In10.Cu" signal "GND4")
		(24 "In11.Cu" signal "IN4")
		(26 "In12.Cu" signal "GND5")
		(28 "In13.Cu" signal "IN5")
		(30 "In14.Cu" signal "GND6")
		(32 "In15.Cu" signal "IN6")
		(34 "In16.Cu" signal "GND7")
		(2 "B.Cu" signal "BOTTOM")
		(9 "F.Adhes" user "F.Adhesive")
		(11 "B.Adhes" user "B.Adhesive")
		(13 "F.Paste" user "Package Geometry/Pastemask Top")
		(15 "B.Paste" user "Package Geometry/Pastemask Bottom")
		(5 "F.SilkS" user "Ref Des/Silkscreen Top")
		(7 "B.SilkS" user "Ref Des/Silkscreen Bottom")
		(1 "F.Mask" user "Board Geometry/Soldermask Top")
		(3 "B.Mask" user "Board Geometry/Soldermask Bottom")
		(17 "Dwgs.User" user "User.Drawings")
		(19 "Cmts.User" user "User.Comments")
		(21 "Eco1.User" user "User.Eco1")
		(23 "Eco2.User" user "User.Eco2")
		(25 "Edge.Cuts" user "Board Geometry/Outline")
		(27 "Margin" user)
		(31 "F.CrtYd" user "Package Geometry/Place Bound Top")
		(29 "B.CrtYd" user "Package Geometry/Place Bound Bottom")
		(35 "F.Fab" user "Ref Des/Assembly Top")
		(33 "B.Fab" user "Ref Des/Assembly Bottom")
	)
	(footprint ""
		(layer "F.Cu")
		(at 165.655244 -370.57203 -90)
		(property "Reference" "C748"
			(at 0 0 270)
			(layer "F.SilkS")
			(hide yes)
			(effects
				(font
					(size 1.27 1.27)
				)
			)
		)
		(property "Value" ""
			(at 0 0 270)
			(layer "F.Fab")
			(effects
				(font
					(size 1.27 1.27)
				)
			)
		)
		(duplicate_pad_numbers_are_jumpers no)
		(fp_line
			(start -0.299974 0.150114)
			(end -0.299974 -0.150114)
			(stroke
				(width 0.1)
				(type default)
			)
			(layer "F.Fab")
		)
		(fp_line
			(start 0.299974 0.150114)
			(end -0.299974 0.150114)
			(stroke
				(width 0.1)
				(type default)
			)
			(layer "F.Fab")
		)
		(fp_line
			(start -0.299974 -0.150114)
			(end 0.299974 -0.150114)
			(stroke
				(width 0.1)
				(type default)
			)
			(layer "F.Fab")
		)
		(fp_line
			(start 0.299974 -0.150114)
			(end 0.299974 0.150114)
			(stroke
				(width 0.1)
				(type default)
			)
			(layer "F.Fab")
		)
		(pad "1" smd rect
			(at -0.2667 0 270)
			(size 0.3048 0.381)
			(layers "F.Cu" "F.Mask" "F.Paste")
			(net "P5E_CPU1_P2_TX_C_DN<12>")
		)
		(pad "2" smd rect
			(at 0.2667 0 270)
			(size 0.3048 0.381)
			(layers "F.Cu" "F.Mask" "F.Paste")
			(net "P5E_CPU1_P2_TX_DN<12>")
		)
	)
	(footprint ""
		(layer "F.Cu")
		(at 70.992746 -386.44068 90)
		(property "Reference" "C115"
			(at 0 0 90)
			(layer "F.SilkS")
			(hide yes)
			(effects
				(font
					(size 1.27 1.27)
				)
			)
		)
		(property "Value" ""
			(at 0 0 90)
			(layer "F.Fab")
			(effects
				(font
					(size 1.27 1.27)
				)
			)
		)
		(duplicate_pad_numbers_are_jumpers no)
		(fp_line
			(start 0.7874 -0.4064)
			(end 0.7874 0.4064)
			(stroke
				(width 0.1524)
				(type default)
			)
			(layer "F.SilkS")
		)
		(fp_line
			(start -0.7874 -0.4064)
			(end 0.7874 -0.4064)
			(stroke
				(width 0.1524)
				(type default)
			)
			(layer "F.SilkS")
		)
		(fp_line
			(start 0.7874 0.4064)
			(end -0.7874 0.4064)
			(stroke
				(width 0.1524)
				(type default)
			)
			(layer "F.SilkS")
		)
		(fp_line
			(start -0.7874 0.4064)
			(end -0.7874 -0.4064)
			(stroke
				(width 0.1524)
				(type default)
			)
			(layer "F.SilkS")
		)
		(fp_line
			(start -0.12065 -0.305054)
			(end -0.12065 -0.2794)
			(stroke
				(width 0.1)
				(type default)
			)
			(layer "F.Fab")
		)
		(fp_line
			(start -0.67945 -0.305054)
			(end -0.12065 -0.305054)
			(stroke
				(width 0.1)
				(type default)
			)
			(layer "F.Fab")
		)
		(fp_line
			(start 0.67945 -0.3048)
			(end 0.67945 0.3048)
			(stroke
				(width 0.1)
				(type default)
			)
			(layer "F.Fab")
		)
		(fp_line
			(start 0.12065 -0.3048)
			(end 0.67945 -0.3048)
			(stroke
				(width 0.1)
				(type default)
			)
			(layer "F.Fab")
		)
		(fp_line
			(start 0.12065 -0.2794)
			(end 0.12065 -0.3048)
			(stroke
				(width 0.1)
				(type default)
			)
			(layer "F.Fab")
		)
		(fp_line
			(start -0.12065 -0.2794)
			(end 0.12065 -0.2794)
			(stroke
				(width 0.1)
				(type default)
			)
			(layer "F.Fab")
		)
		(fp_line
			(start 0.120396 0.2794)
			(end -0.12065 0.2794)
			(stroke
				(width 0.1)
				(type default)
			)
			(layer "F.Fab")
		)
		(fp_line
			(start -0.12065 0.2794)
			(end -0.12065 0.3048)
			(stroke
				(width 0.1)
				(type default)
			)
			(layer "F.Fab")
		)
		(fp_line
			(start 0.67945 0.3048)
			(end 0.120396 0.3048)
			(stroke
				(width 0.1)
				(type default)
			)
			(layer "F.Fab")
		)
		(fp_line
			(start 0.120396 0.3048)
			(end 0.120396 0.2794)
			(stroke
				(width 0.1)
				(type default)
			)
			(layer "F.Fab")
		)
		(fp_line
			(start -0.12065 0.3048)
			(end -0.67945 0.3048)
			(stroke
				(width 0.1)
				(type default)
			)
			(layer "F.Fab")
		)
		(fp_line
			(start -0.67945 0.3048)
			(end -0.67945 -0.305054)
			(stroke
				(width 0.1)
				(type default)
			)
			(layer "F.Fab")
		)
		(pad "1" smd circle
			(at -0.40005 0 90)
			(size 0 0)
			(layers "F.Cu" "F.Mask" "F.Paste")
			(net "P1V8_CPU1_RT_1D")
		)
		(pad "2" smd circle
			(at 0.40005 0 90)
			(size 0 0)
			(layers "F.Cu" "F.Mask" "F.Paste")
			(net "GND")
		)
	)
	(footprint ""
		(layer "F.Cu")
		(at 344.067638 -161.056574 90)
		(property "Reference" "PC154_6"
			(at 0 0 90)
			(layer "F.SilkS")
			(hide yes)
			(effects
				(font
					(size 1.27 1.27)
				)
			)
		)
		(property "Value" ""
			(at 0 0 90)
			(layer "F.Fab")
			(effects
				(font
					(size 1.27 1.27)
				)
			)
		)
		(duplicate_pad_numbers_are_jumpers no)
		(fp_line
			(start 0.7874 -0.4064)
			(end 0.7874 0.4064)
			(stroke
				(width 0.1524)
				(type default)
			)
			(layer "F.SilkS")
		)
		(fp_line
			(start -0.7874 -0.4064)
			(end 0.7874 -0.4064)
			(stroke
				(width 0.1524)
				(type default)
			)
			(layer "F.SilkS")
		)
		(fp_line
			(start 0.7874 0.4064)
			(end -0.7874 0.4064)
			(stroke
				(width 0.1524)
				(type default)
			)
			(layer "F.SilkS")
		)
		(fp_line
			(start -0.7874 0.4064)
			(end -0.7874 -0.4064)
			(stroke
				(width 0.1524)
				(type default)
			)
			(layer "F.SilkS")
		)
		(fp_line
			(start -0.12065 -0.305054)
			(end -0.12065 -0.2794)
			(stroke
				(width 0.1)
				(type default)
			)
			(layer "F.Fab")
		)
		(fp_line
			(start -0.67945 -0.305054)
			(end -0.12065 -0.305054)
			(stroke
				(width 0.1)
				(type default)
			)
			(layer "F.Fab")
		)
		(fp_line
			(start 0.67945 -0.3048)
			(end 0.67945 0.3048)
			(stroke
				(width 0.1)
				(type default)
			)
			(layer "F.Fab")
		)
		(fp_line
			(start 0.12065 -0.3048)
			(end 0.67945 -0.3048)
			(stroke
				(width 0.1)
				(type default)
			)
			(layer "F.Fab")
		)
		(fp_line
			(start 0.12065 -0.2794)
			(end 0.12065 -0.3048)
			(stroke
				(width 0.1)
				(type default)
			)
			(layer "F.Fab")
		)
		(fp_line
			(start -0.12065 -0.2794)
			(end 0.12065 -0.2794)
			(stroke
				(width 0.1)
				(type default)
			)
			(layer "F.Fab")
		)
		(fp_line
			(start 0.120396 0.2794)
			(end -0.12065 0.2794)
			(stroke
				(width 0.1)
				(type default)
			)
			(layer "F.Fab")
		)
		(fp_line
			(start -0.12065 0.2794)
			(end -0.12065 0.3048)
			(stroke
				(width 0.1)
				(type default)
			)
			(layer "F.Fab")
		)
		(fp_line
			(start 0.67945 0.3048)
			(end 0.120396 0.3048)
			(stroke
				(width 0.1)
				(type default)
			)
			(layer "F.Fab")
		)
		(fp_line
			(start 0.120396 0.3048)
			(end 0.120396 0.2794)
			(stroke
				(width 0.1)
				(type default)
			)
			(layer "F.Fab")
		)
		(fp_line
			(start -0.12065 0.3048)
			(end -0.67945 0.3048)
			(stroke
				(width 0.1)
				(type default)
			)
			(layer "F.Fab")
		)
		(fp_line
			(start -0.67945 0.3048)
			(end -0.67945 -0.305054)
			(stroke
				(width 0.1)
				(type default)
			)
			(layer "F.Fab")
		)
		(pad "1" smd circle
			(at -0.40005 0 90)
			(size 0 0)
			(layers "F.Cu" "F.Mask" "F.Paste")
			(net "SW_P12V_AUX_PVDDCR_CPU0_P0_FLT")
		)
		(pad "2" smd circle
			(at 0.40005 0 90)
			(size 0 0)
			(layers "F.Cu" "F.Mask" "F.Paste")
			(net "GND")
		)
	)
	(footprint ""
		(layer "F.Cu")
		(at 36.99891 -337.403948)
		(property "Reference" "PL68"
			(at -3.115056 -15.887446 0)
			(unlocked yes)
			(layer "F.SilkS")
			(effects
				(font
					(size 0.7874 0.5842)
					(thickness 0.1524)
				)
				(justify left)
			)
		)
		(property "Value" ""
			(at 0 0 0)
			(layer "F.Fab")
			(effects
				(font
					(size 1.27 1.27)
				)
			)
		)
		(duplicate_pad_numbers_are_jumpers no)
		(fp_line
			(start -3.750056 -5.500116)
			(end -2.393442 -5.500116)
			(stroke
				(width 0.1524)
				(type default)
			)
			(layer "F.SilkS")
		)
		(fp_line
			(start -3.750056 5.500116)
			(end -3.750056 -5.500116)
			(stroke
				(width 0.1524)
				(type default)
			)
			(layer "F.SilkS")
		)
		(fp_line
			(start -2.393442 5.500116)
			(end -3.750056 5.500116)
			(stroke
				(width 0.1524)
				(type default)
			)
			(layer "F.SilkS")
		)
		(fp_line
			(start 2.393442 5.500116)
			(end 3.750056 5.500116)
			(stroke
				(width 0.1524)
				(type default)
			)
			(layer "F.SilkS")
		)
		(fp_line
			(start 3.750056 -5.500116)
			(end 2.393442 -5.500116)
			(stroke
				(width 0.1524)
				(type default)
			)
			(layer "F.SilkS")
		)
		(fp_line
			(start 3.750056 5.500116)
			(end 3.750056 -5.500116)
			(stroke
				(width 0.1524)
				(type default)
			)
			(layer "F.SilkS")
		)
		(fp_poly
			(pts
				(xy -3.9116 -4.249928) (xy -4.35991 -4.0259) (xy -4.35991 -4.473956)
			)
			(stroke
				(width 0)
				(type default)
			)
			(fill yes)
			(layer "F.SilkS")
		)
		(fp_line
			(start -3.750056 -5.500116)
			(end -3.750056 5.500116)
			(stroke
				(width 0.1)
				(type default)
			)
			(layer "F.Fab")
		)
		(fp_line
			(start -3.750056 5.500116)
			(end 3.750056 5.500116)
			(stroke
				(width 0.1)
				(type default)
			)
			(layer "F.Fab")
		)
		(fp_line
			(start 3.750056 -5.500116)
			(end -3.750056 -5.500116)
			(stroke
				(width 0.1)
				(type default)
			)
			(layer "F.Fab")
		)
		(fp_line
			(start 3.750056 5.500116)
			(end 3.750056 -5.500116)
			(stroke
				(width 0.1)
				(type default)
			)
			(layer "F.Fab")
		)
		(fp_poly
			(pts
				(xy -4.9276 -4.757928) (xy -4.9276 -3.741928) (xy -3.9116 -4.249928)
			)
			(stroke
				(width 0)
				(type default)
			)
			(fill yes)
			(layer "F.Fab")
		)
		(pad "1" smd rect
			(at 0 -4.249928 270)
			(size 2.413 4.5212)
			(layers "F.Cu" "F.Mask" "F.Paste")
			(net "SW_PVDDIO_P1_SW3")
		)
		(pad "2" smd rect
			(at 0 -1.175004 270)
			(size 1.3716 4.5212)
			(layers "F.Cu" "F.Mask" "F.Paste")
			(net "IND_PVDDIO_P1_CPL4")
		)
		(pad "3" smd rect
			(at 0 1.175004 270)
			(size 1.3716 4.5212)
			(layers "F.Cu" "F.Mask" "F.Paste")
			(net "IND_PVDDIO_P1_CPL3")
		)
		(pad "4" smd rect
			(at 0 4.249928 270)
			(size 2.413 4.5212)
			(layers "F.Cu" "F.Mask" "F.Paste")
			(net "PVDDIO_P1")
		)
	)
	(footprint ""
		(layer "F.Cu")
		(at 157.692852 -351.247456 180)
		(property "Reference" "C8641"
			(at 0 0 180)
			(layer "F.SilkS")
			(hide yes)
			(effects
				(font
					(size 1.27 1.27)
				)
			)
		)
		(property "Value" ""
			(at 0 0 180)
			(layer "F.Fab")
			(effects
				(font
					(size 1.27 1.27)
				)
			)
		)
		(duplicate_pad_numbers_are_jumpers no)
		(fp_line
			(start 0.7874 0.4064)
			(end -0.7874 0.4064)
			(stroke
				(width 0.1524)
				(type default)
			)
			(layer "F.SilkS")
		)
		(fp_line
			(start 0.7874 -0.4064)
			(end 0.7874 0.4064)
			(stroke
				(width 0.1524)
				(type default)
			)
			(layer "F.SilkS")
		)
		(fp_line
			(start -0.7874 0.4064)
			(end -0.7874 -0.4064)
			(stroke
				(width 0.1524)
				(type default)
			)
			(layer "F.SilkS")
		)
		(fp_line
			(start -0.7874 -0.4064)
			(end 0.7874 -0.4064)
			(stroke
				(width 0.1524)
				(type default)
			)
			(layer "F.SilkS")
		)
		(fp_line
			(start 0.67945 0.3048)
			(end 0.120396 0.3048)
			(stroke
				(width 0.1)
				(type default)
			)
			(layer "F.Fab")
		)
		(fp_line
			(start 0.67945 -0.3048)
			(end 0.67945 0.3048)
			(stroke
				(width 0.1)
				(type default)
			)
			(layer "F.Fab")
		)
		(fp_line
			(start 0.12065 -0.2794)
			(end 0.12065 -0.3048)
			(stroke
				(width 0.1)
				(type default)
			)
			(layer "F.Fab")
		)
		(fp_line
			(start 0.12065 -0.3048)
			(end 0.67945 -0.3048)
			(stroke
				(width 0.1)
				(type default)
			)
			(layer "F.Fab")
		)
		(fp_line
			(start 0.120396 0.3048)
			(end 0.120396 0.2794)
			(stroke
				(width 0.1)
				(type default)
			)
			(layer "F.Fab")
		)
		(fp_line
			(start 0.120396 0.2794)
			(end -0.12065 0.2794)
			(stroke
				(width 0.1)
				(type default)
			)
			(layer "F.Fab")
		)
		(fp_line
			(start -0.12065 0.3048)
			(end -0.67945 0.3048)
			(stroke
				(width 0.1)
				(type default)
			)
			(layer "F.Fab")
		)
		(fp_line
			(start -0.12065 0.2794)
			(end -0.12065 0.3048)
			(stroke
				(width 0.1)
				(type default)
			)
			(layer "F.Fab")
		)
		(fp_line
			(start -0.12065 -0.2794)
			(end 0.12065 -0.2794)
			(stroke
				(width 0.1)
				(type default)
			)
			(layer "F.Fab")
		)
		(fp_line
			(start -0.12065 -0.305054)
			(end -0.12065 -0.2794)
			(stroke
				(width 0.1)
				(type default)
			)
			(layer "F.Fab")
		)
		(fp_line
			(start -0.67945 0.3048)
			(end -0.67945 -0.305054)
			(stroke
				(width 0.1)
				(type default)
			)
			(layer "F.Fab")
		)
		(fp_line
			(start -0.67945 -0.305054)
			(end -0.12065 -0.305054)
			(stroke
				(width 0.1)
				(type default)
			)
			(layer "F.Fab")
		)
		(pad "1" smd circle
			(at -0.40005 0 180)
			(size 0 0)
			(layers "F.Cu" "F.Mask" "F.Paste")
			(net "PWRGD_PVDD11_S3_P1_R")
		)
		(pad "2" smd circle
			(at 0.40005 0 180)
			(size 0 0)
			(layers "F.Cu" "F.Mask" "F.Paste")
			(net "GND")
		)
	)
	(footprint ""
		(layer "F.Cu")
		(at 429.171354 -397.135604)
		(property "Reference" "C669"
			(at 0 0 0)
			(layer "F.SilkS")
			(hide yes)
			(effects
				(font
					(size 1.27 1.27)
				)
			)
		)
		(property "Value" ""
			(at 0 0 0)
			(layer "F.Fab")
			(effects
				(font
					(size 1.27 1.27)
				)
			)
		)
		(duplicate_pad_numbers_are_jumpers no)
		(fp_line
			(start -0.7874 -0.4064)
			(end 0.7874 -0.4064)
			(stroke
				(width 0.1524)
				(type default)
			)
			(layer "F.SilkS")
		)
		(fp_line
			(start -0.7874 0.4064)
			(end -0.7874 -0.4064)
			(stroke
				(width 0.1524)
				(type default)
			)
			(layer "F.SilkS")
		)
		(fp_line
			(start 0.7874 -0.4064)
			(end 0.7874 0.4064)
			(stroke
				(width 0.1524)
				(type default)
			)
			(layer "F.SilkS")
		)
		(fp_line
			(start 0.7874 0.4064)
			(end -0.7874 0.4064)
			(stroke
				(width 0.1524)
				(type default)
			)
			(layer "F.SilkS")
		)
		(fp_line
			(start -0.67945 -0.305054)
			(end -0.12065 -0.305054)
			(stroke
				(width 0.1)
				(type default)
			)
			(layer "F.Fab")
		)
		(fp_line
			(start -0.67945 0.3048)
			(end -0.67945 -0.305054)
			(stroke
				(width 0.1)
				(type default)
			)
			(layer "F.Fab")
		)
		(fp_line
			(start -0.12065 -0.305054)
			(end -0.12065 -0.2794)
			(stroke
				(width 0.1)
				(type default)
			)
			(layer "F.Fab")
		)
		(fp_line
			(start -0.12065 -0.2794)
			(end 0.12065 -0.2794)
			(stroke
				(width 0.1)
				(type default)
			)
			(layer "F.Fab")
		)
		(fp_line
			(start -0.12065 0.2794)
			(end -0.12065 0.3048)
			(stroke
				(width 0.1)
				(type default)
			)
			(layer "F.Fab")
		)
		(fp_line
			(start -0.12065 0.3048)
			(end -0.67945 0.3048)
			(stroke
				(width 0.1)
				(type default)
			)
			(layer "F.Fab")
		)
		(fp_line
			(start 0.120396 0.2794)
			(end -0.12065 0.2794)
			(stroke
				(width 0.1)
				(type default)
			)
			(layer "F.Fab")
		)
		(fp_line
			(start 0.120396 0.3048)
			(end 0.120396 0.2794)
			(stroke
				(width 0.1)
				(type default)
			)
			(layer "F.Fab")
		)
		(fp_line
			(start 0.12065 -0.3048)
			(end 0.67945 -0.3048)
			(stroke
				(width 0.1)
				(type default)
			)
			(layer "F.Fab")
		)
		(fp_line
			(start 0.12065 -0.2794)
			(end 0.12065 -0.3048)
			(stroke
				(width 0.1)
				(type default)
			)
			(layer "F.Fab")
		)
		(fp_line
			(start 0.67945 -0.3048)
			(end 0.67945 0.3048)
			(stroke
				(width 0.1)
				(type default)
			)
			(layer "F.Fab")
		)
		(fp_line
			(start 0.67945 0.3048)
			(end 0.120396 0.3048)
			(stroke
				(width 0.1)
				(type default)
			)
			(layer "F.Fab")
		)
		(pad "1" smd circle
			(at -0.40005 0)
			(size 0 0)
			(layers "F.Cu" "F.Mask" "F.Paste")
			(net "P1V8_CPU0_RT_1D")
		)
		(pad "2" smd circle
			(at 0.40005 0)
			(size 0 0)
			(layers "F.Cu" "F.Mask" "F.Paste")
			(net "GND")
		)
	)
	(footprint ""
		(layer "F.Cu")
		(at 23.012654 -351.609406 90)
		(property "Reference" "PR341"
			(at 0 0 90)
			(layer "F.SilkS")
			(hide yes)
			(effects
				(font
					(size 1.27 1.27)
				)
			)
		)
		(property "Value" ""
			(at 0 0 90)
			(layer "F.Fab")
			(effects
				(font
					(size 1.27 1.27)
				)
			)
		)
		(duplicate_pad_numbers_are_jumpers no)
		(fp_line
			(start 0.7874 -0.4064)
			(end 0.7874 0.4064)
			(stroke
				(width 0.1524)
				(type default)
			)
			(layer "F.SilkS")
		)
		(fp_line
			(start -0.7874 -0.4064)
			(end 0.7874 -0.4064)
			(stroke
				(width 0.1524)
				(type default)
			)
			(layer "F.SilkS")
		)
		(fp_line
			(start 0.7874 0.4064)
			(end -0.7874 0.4064)
			(stroke
				(width 0.1524)
				(type default)
			)
			(layer "F.SilkS")
		)
		(fp_line
			(start -0.7874 0.4064)
			(end -0.7874 -0.4064)
			(stroke
				(width 0.1524)
				(type default)
			)
			(layer "F.SilkS")
		)
		(fp_line
			(start -0.12065 -0.305054)
			(end -0.12065 -0.2794)
			(stroke
				(width 0.1)
				(type default)
			)
			(layer "F.Fab")
		)
		(fp_line
			(start -0.67945 -0.305054)
			(end -0.12065 -0.305054)
			(stroke
				(width 0.1)
				(type default)
			)
			(layer "F.Fab")
		)
		(fp_line
			(start 0.67945 -0.3048)
			(end 0.67945 0.3048)
			(stroke
				(width 0.1)
				(type default)
			)
			(layer "F.Fab")
		)
		(fp_line
			(start 0.12065 -0.3048)
			(end 0.67945 -0.3048)
			(stroke
				(width 0.1)
				(type default)
			)
			(layer "F.Fab")
		)
		(fp_line
			(start 0.12065 -0.2794)
			(end 0.12065 -0.3048)
			(stroke
				(width 0.1)
				(type default)
			)
			(layer "F.Fab")
		)
		(fp_line
			(start -0.12065 -0.2794)
			(end 0.12065 -0.2794)
			(stroke
				(width 0.1)
				(type default)
			)
			(layer "F.Fab")
		)
		(fp_line
			(start 0.120396 0.2794)
			(end -0.12065 0.2794)
			(stroke
				(width 0.1)
				(type default)
			)
			(layer "F.Fab")
		)
		(fp_line
			(start -0.12065 0.2794)
			(end -0.12065 0.3048)
			(stroke
				(width 0.1)
				(type default)
			)
			(layer "F.Fab")
		)
		(fp_line
			(start 0.67945 0.3048)
			(end 0.120396 0.3048)
			(stroke
				(width 0.1)
				(type default)
			)
			(layer "F.Fab")
		)
		(fp_line
			(start 0.120396 0.3048)
			(end 0.120396 0.2794)
			(stroke
				(width 0.1)
				(type default)
			)
			(layer "F.Fab")
		)
		(fp_line
			(start -0.12065 0.3048)
			(end -0.67945 0.3048)
			(stroke
				(width 0.1)
				(type default)
			)
			(layer "F.Fab")
		)
		(fp_line
			(start -0.67945 0.3048)
			(end -0.67945 -0.305054)
			(stroke
				(width 0.1)
				(type default)
			)
			(layer "F.Fab")
		)
		(pad "1" smd circle
			(at -0.40005 0 90)
			(size 0 0)
			(layers "F.Cu" "F.Mask" "F.Paste")
			(net "PVDDCR_CPU1_P1_PVCC")
		)
		(pad "2" smd circle
			(at 0.40005 0 90)
			(size 0 0)
			(layers "F.Cu" "F.Mask" "F.Paste")
			(net "P3V3_AUX")
		)
	)
)
